(kicad_pcb
	(version 20241229)
	(generator "pcbnew")
	(generator_version "9.0")
	(general
		(thickness 1.292)
		(legacy_teardrops no)
	)
	(paper "A4")
	(title_block
		(title "LPDDR5 Testbed")
		(date "2023-12-19")
		(rev "1.0.0")
		(comment 9 "footprints 24-30 of 160")
	)
	(layers
		(0 "F.Cu" signal)
		(4 "In1.Cu" power)
		(6 "In2.Cu" power)
		(8 "In3.Cu" signal)
		(10 "In4.Cu" signal)
		(2 "B.Cu" signal)
		(9 "F.Adhes" user "F.Adhesive")
		(11 "B.Adhes" user "B.Adhesive")
		(13 "F.Paste" user)
		(15 "B.Paste" user)
		(5 "F.SilkS" user "F.Silkscreen")
		(7 "B.SilkS" user "B.Silkscreen")
		(1 "F.Mask" user)
		(3 "B.Mask" user)
		(17 "Dwgs.User" user "User.Drawings")
		(19 "Cmts.User" user "User.Comments")
		(21 "Eco1.User" user "User.Eco1")
		(23 "Eco2.User" user "User.Eco2")
		(25 "Edge.Cuts" user)
		(27 "Margin" user)
		(31 "F.CrtYd" user "F.Courtyard")
		(29 "B.CrtYd" user "B.Courtyard")
		(35 "F.Fab" user)
		(33 "B.Fab" user)
	)
	(footprint "antmicro-footprints:C_0402_1005Metric"
		(layer "F.Cu")
		(at 167.6 67.45 180)
		(descr "Capacitor SMD 0402")
		(tags "capacitor SMD 0402")
		(property "Reference" "C13"
			(at -1.1 -8.95 0)
			(unlocked yes)
			(layer "F.SilkS")
			(effects
				(font
					(size 0.7 0.7)
					(thickness 0.15)
				)
				(justify right bottom)
			)
		)
		(property "Value" "C_10n_0402"
			(at -1.022927 2.155213 0)
			(layer "F.Fab")
			(effects
				(font
					(size 0.7 0.7)
					(thickness 0.15)
				)
				(justify right bottom)
			)
		)
		(property "Author" "Antmicro"
			(at 335.2 134.9 0)
			(layer "F.Fab")
			(hide yes)
			(effects
				(font
					(size 1 1)
					(thickness 0.15)
				)
			)
		)
		(property "Dielectric" "X7R"
			(at 335.2 134.9 0)
			(layer "F.Fab")
			(hide yes)
			(effects
				(font
					(size 1 1)
					(thickness 0.15)
				)
			)
		)
		(property "License" "Apache-2.0"
			(at 335.2 134.9 0)
			(layer "F.Fab")
			(hide yes)
			(effects
				(font
					(size 1 1)
					(thickness 0.15)
				)
			)
		)
		(property "MPN" "GRM155R71H103KA88D"
			(at 335.2 134.9 0)
			(layer "F.Fab")
			(hide yes)
			(effects
				(font
					(size 1 1)
					(thickness 0.15)
				)
			)
		)
		(property "Manufacturer" "Murata"
			(at 335.2 134.9 0)
			(layer "F.Fab")
			(hide yes)
			(effects
				(font
					(size 1 1)
					(thickness 0.15)
				)
			)
		)
		(property "Val" "10n"
			(at 335.2 134.9 0)
			(layer "F.Fab")
			(hide yes)
			(effects
				(font
					(size 1 1)
					(thickness 0.15)
				)
			)
		)
		(property "Voltage" "50V"
			(at 335.2 134.9 0)
			(layer "F.Fab")
			(hide yes)
			(effects
				(font
					(size 1 1)
					(thickness 0.15)
				)
			)
		)
		(sheetname "Power supply")
		(sheetfile "power_supply.kicad_sch")
		(attr smd)
		(fp_rect
			(start -0.9659 -0.481258)
			(end 0.9649 0.458742)
			(stroke
				(width 0.05)
				(type solid)
			)
			(fill no)
			(layer "F.CrtYd")
		)
		(fp_line
			(start 0.499 0.248)
			(end -0.499 0.248)
			(stroke
				(width 0.15)
				(type solid)
			)
			(layer "F.Fab")
		)
		(fp_line
			(start 0.499 -0.25)
			(end 0.499 0.248)
			(stroke
				(width 0.15)
				(type solid)
			)
			(layer "F.Fab")
		)
		(fp_line
			(start -0.499 0.248)
			(end -0.499 -0.25)
			(stroke
				(width 0.15)
				(type solid)
			)
			(layer "F.Fab")
		)
		(fp_line
			(start -0.499 -0.25)
			(end 0.499 -0.25)
			(stroke
				(width 0.15)
				(type solid)
			)
			(layer "F.Fab")
		)
		(pad "1" smd roundrect
			(at -0.484 0 180)
			(size 0.59 0.64)
			(layers "F.Cu" "F.Mask" "F.Paste")
			(roundrect_rratio 0.25)
			(net 14 "GND")
			(pintype "passive")
		)
		(pad "2" smd roundrect
			(at 0.484 0 180)
			(size 0.59 0.64)
			(layers "F.Cu" "F.Mask" "F.Paste")
			(roundrect_rratio 0.25)
			(net 6 "Net-(C13-Pad2)")
			(pintype "passive")
		)
	)
	(footprint "antmicro-footprints:R_0402_1005Metric"
		(layer "F.Cu")
		(at 161.55 61.9 90)
		(descr "Resistor SMD 0402")
		(tags "resistor SMD 0402")
		(property "Reference" "R3"
			(at -0.7 -0.65 90)
			(unlocked yes)
			(layer "F.SilkS")
			(effects
				(font
					(size 0.7 0.7)
					(thickness 0.15)
				)
				(justify left bottom)
			)
		)
		(property "Value" "R_0R_0402"
			(at -1.011843 1.772047 90)
			(layer "F.Fab")
			(effects
				(font
					(size 0.7 0.7)
					(thickness 0.15)
				)
				(justify left bottom)
			)
		)
		(property "Author" "Antmicro"
			(at 223.45 -99.65 0)
			(layer "F.Fab")
			(hide yes)
			(effects
				(font
					(size 1 1)
					(thickness 0.15)
				)
			)
		)
		(property "Current" "1A"
			(at 223.45 -99.65 0)
			(layer "F.Fab")
			(hide yes)
			(effects
				(font
					(size 1 1)
					(thickness 0.15)
				)
			)
		)
		(property "License" "Apache-2.0"
			(at 223.45 -99.65 0)
			(layer "F.Fab")
			(hide yes)
			(effects
				(font
					(size 1 1)
					(thickness 0.15)
				)
			)
		)
		(property "MPN" "ERJ2GE0R00X"
			(at 223.45 -99.65 0)
			(layer "F.Fab")
			(hide yes)
			(effects
				(font
					(size 1 1)
					(thickness 0.15)
				)
			)
		)
		(property "Manufacturer" "Panasonic"
			(at 223.45 -99.65 0)
			(layer "F.Fab")
			(hide yes)
			(effects
				(font
					(size 1 1)
					(thickness 0.15)
				)
			)
		)
		(property "Tolerance" ""
			(at 223.45 -99.65 0)
			(layer "F.Fab")
			(hide yes)
			(effects
				(font
					(size 1 1)
					(thickness 0.15)
				)
			)
		)
		(property "Val" "0R"
			(at 223.45 -99.65 0)
			(layer "F.Fab")
			(hide yes)
			(effects
				(font
					(size 1 1)
					(thickness 0.15)
				)
			)
		)
		(sheetname "Power supply")
		(sheetfile "power_supply.kicad_sch")
		(attr smd)
		(fp_rect
			(start -0.93 -0.47)
			(end 0.93 0.47)
			(stroke
				(width 0.05)
				(type solid)
			)
			(fill no)
			(layer "F.CrtYd")
		)
		(fp_rect
			(start -0.5 -0.25)
			(end 0.5 0.25)
			(stroke
				(width 0.15)
				(type solid)
			)
			(fill no)
			(layer "F.Fab")
		)
		(pad "1" smd roundrect
			(at -0.485 0 90)
			(size 0.59 0.64)
			(layers "F.Cu" "F.Mask" "F.Paste")
			(roundrect_rratio 0.25)
			(net 61 "Net-(R29-Pad2)")
			(pintype "passive")
		)
		(pad "2" smd roundrect
			(at 0.485 0 90)
			(size 0.59 0.64)
			(layers "F.Cu" "F.Mask" "F.Paste")
			(roundrect_rratio 0.25)
			(net 228 "/Power supply/DCDC_PWRGD")
			(pintype "passive")
		)
	)
	(footprint "antmicro-footprints:R_0402_1005Metric"
		(layer "F.Cu")
		(at 168.875 61.45 -90)
		(descr "Resistor SMD 0402")
		(tags "resistor SMD 0402")
		(property "Reference" "R42"
			(at 9.45 -0.125 90)
			(unlocked yes)
			(layer "F.SilkS")
			(effects
				(font
					(size 0.7 0.7)
					(thickness 0.15)
				)
				(justify right bottom)
			)
		)
		(property "Value" "R_1k_0402"
			(at -1.011843 1.772047 90)
			(layer "F.Fab")
			(effects
				(font
					(size 0.7 0.7)
					(thickness 0.15)
				)
				(justify right bottom)
			)
		)
		(property "Author" "Antmicro"
			(at 107.425 230.325 0)
			(layer "F.Fab")
			(hide yes)
			(effects
				(font
					(size 1 1)
					(thickness 0.15)
				)
			)
		)
		(property "License" "Apache-2.0"
			(at 107.425 230.325 0)
			(layer "F.Fab")
			(hide yes)
			(effects
				(font
					(size 1 1)
					(thickness 0.15)
				)
			)
		)
		(property "MPN" "CR0402-FX-1001GLF"
			(at 107.425 230.325 0)
			(layer "F.Fab")
			(hide yes)
			(effects
				(font
					(size 1 1)
					(thickness 0.15)
				)
			)
		)
		(property "Manufacturer" "Bourns"
			(at 107.425 230.325 0)
			(layer "F.Fab")
			(hide yes)
			(effects
				(font
					(size 1 1)
					(thickness 0.15)
				)
			)
		)
		(property "Tolerance" "1%"
			(at 107.425 230.325 0)
			(layer "F.Fab")
			(hide yes)
			(effects
				(font
					(size 1 1)
					(thickness 0.15)
				)
			)
		)
		(property "Val" "1k"
			(at 107.425 230.325 0)
			(layer "F.Fab")
			(hide yes)
			(effects
				(font
					(size 1 1)
					(thickness 0.15)
				)
			)
		)
		(sheetname "Power supply")
		(sheetfile "power_supply.kicad_sch")
		(attr smd)
		(fp_rect
			(start -0.93 -0.47)
			(end 0.93 0.47)
			(stroke
				(width 0.05)
				(type solid)
			)
			(fill no)
			(layer "F.CrtYd")
		)
		(fp_rect
			(start -0.5 -0.25)
			(end 0.5 0.25)
			(stroke
				(width 0.15)
				(type solid)
			)
			(fill no)
			(layer "F.Fab")
		)
		(pad "1" smd roundrect
			(at -0.485 0 270)
			(size 0.59 0.64)
			(layers "F.Cu" "F.Mask" "F.Paste")
			(roundrect_rratio 0.25)
			(net 5 "+5V")
			(pintype "passive")
		)
		(pad "2" smd roundrect
			(at 0.485 0 270)
			(size 0.59 0.64)
			(layers "F.Cu" "F.Mask" "F.Paste")
			(roundrect_rratio 0.25)
			(net 16 "Net-(D2-Pad1)")
			(pintype "passive")
		)
	)
	(footprint "antmicro-footprints:R_0402_1005Metric"
		(layer "F.Cu")
		(at 103.3 73.75 180)
		(descr "Resistor SMD 0402")
		(tags "resistor SMD 0402")
		(property "Reference" "R40"
			(at -0.9 -2.45 0)
			(unlocked yes)
			(layer "F.SilkS")
			(effects
				(font
					(size 0.7 0.7)
					(thickness 0.15)
				)
				(justify right bottom)
			)
		)
		(property "Value" "R_120k_0402"
			(at -1.011843 1.772047 0)
			(layer "F.Fab")
			(effects
				(font
					(size 0.7 0.7)
					(thickness 0.15)
				)
				(justify right bottom)
			)
		)
		(property "Author" "Antmicro"
			(at 206.6 147.5 0)
			(layer "F.Fab")
			(hide yes)
			(effects
				(font
					(size 1 1)
					(thickness 0.15)
				)
			)
		)
		(property "License" "Apache-2.0"
			(at 206.6 147.5 0)
			(layer "F.Fab")
			(hide yes)
			(effects
				(font
					(size 1 1)
					(thickness 0.15)
				)
			)
		)
		(property "MPN" "CR0402-FX-1203GLF"
			(at 206.6 147.5 0)
			(layer "F.Fab")
			(hide yes)
			(effects
				(font
					(size 1 1)
					(thickness 0.15)
				)
			)
		)
		(property "Manufacturer" "Bourns"
			(at 206.6 147.5 0)
			(layer "F.Fab")
			(hide yes)
			(effects
				(font
					(size 1 1)
					(thickness 0.15)
				)
			)
		)
		(property "Tolerance" "1%"
			(at 206.6 147.5 0)
			(layer "F.Fab")
			(hide yes)
			(effects
				(font
					(size 1 1)
					(thickness 0.15)
				)
			)
		)
		(property "Val" "120k"
			(at 206.6 147.5 0)
			(layer "F.Fab")
			(hide yes)
			(effects
				(font
					(size 1 1)
					(thickness 0.15)
				)
			)
		)
		(sheetname "Power supply")
		(sheetfile "power_supply.kicad_sch")
		(attr smd)
		(fp_rect
			(start -0.93 -0.47)
			(end 0.93 0.47)
			(stroke
				(width 0.05)
				(type solid)
			)
			(fill no)
			(layer "F.CrtYd")
		)
		(fp_rect
			(start -0.5 -0.25)
			(end 0.5 0.25)
			(stroke
				(width 0.15)
				(type solid)
			)
			(fill no)
			(layer "F.Fab")
		)
		(pad "1" smd roundrect
			(at -0.485 0 180)
			(size 0.59 0.64)
			(layers "F.Cu" "F.Mask" "F.Paste")
			(roundrect_rratio 0.25)
			(net 73 "/Power supply/FB4")
			(pintype "passive")
		)
		(pad "2" smd roundrect
			(at 0.485 0 180)
			(size 0.59 0.64)
			(layers "F.Cu" "F.Mask" "F.Paste")
			(roundrect_rratio 0.25)
			(net 14 "GND")
			(pintype "passive")
		)
	)
	(footprint "antmicro-footprints:R_0402_1005Metric"
		(layer "F.Cu")
		(at 132.1 93.8 90)
		(descr "Resistor SMD 0402")
		(tags "resistor SMD 0402")
		(property "Reference" "R59"
			(at -1.122484 1.5 90)
			(unlocked yes)
			(layer "F.SilkS")
			(effects
				(font
					(size 0.7 0.7)
					(thickness 0.15)
				)
				(justify left bottom)
			)
		)
		(property "Value" "R_100R_0402"
			(at -1.011843 1.772047 90)
			(layer "F.Fab")
			(effects
				(font
					(size 0.7 0.7)
					(thickness 0.15)
				)
				(justify left bottom)
			)
		)
		(property "Author" "Antmicro"
			(at 225.9 -38.3 0)
			(layer "F.Fab")
			(hide yes)
			(effects
				(font
					(size 1 1)
					(thickness 0.15)
				)
			)
		)
		(property "License" "Apache-2.0"
			(at 225.9 -38.3 0)
			(layer "F.Fab")
			(hide yes)
			(effects
				(font
					(size 1 1)
					(thickness 0.15)
				)
			)
		)
		(property "MPN" "CR0402-FX-1000GLF"
			(at 225.9 -38.3 0)
			(layer "F.Fab")
			(hide yes)
			(effects
				(font
					(size 1 1)
					(thickness 0.15)
				)
			)
		)
		(property "Manufacturer" "Bourns"
			(at 225.9 -38.3 0)
			(layer "F.Fab")
			(hide yes)
			(effects
				(font
					(size 1 1)
					(thickness 0.15)
				)
			)
		)
		(property "Tolerance" "1%"
			(at 225.9 -38.3 0)
			(layer "F.Fab")
			(hide yes)
			(effects
				(font
					(size 1 1)
					(thickness 0.15)
				)
			)
		)
		(property "Val" "100R"
			(at 225.9 -38.3 0)
			(layer "F.Fab")
			(hide yes)
			(effects
				(font
					(size 1 1)
					(thickness 0.15)
				)
			)
		)
		(sheetname "Translators")
		(sheetfile "translators.kicad_sch")
		(attr smd)
		(fp_rect
			(start -0.93 -0.47)
			(end 0.93 0.47)
			(stroke
				(width 0.05)
				(type solid)
			)
			(fill no)
			(layer "F.CrtYd")
		)
		(fp_rect
			(start -0.5 -0.25)
			(end 0.5 0.25)
			(stroke
				(width 0.15)
				(type solid)
			)
			(fill no)
			(layer "F.Fab")
		)
		(pad "1" smd roundrect
			(at -0.485 0 90)
			(size 0.59 0.64)
			(layers "F.Cu" "F.Mask" "F.Paste")
			(roundrect_rratio 0.25)
			(net 157 "/SODIMM/LPDDR5_IN_A.CA6")
			(pintype "passive")
		)
		(pad "2" smd roundrect
			(at 0.485 0 90)
			(size 0.59 0.64)
			(layers "F.Cu" "F.Mask" "F.Paste")
			(roundrect_rratio 0.25)
			(net 55 "/LPDDR5/LPDDR5_A.CA6")
			(pintype "passive")
		)
	)
	(footprint "antmicro-footprints:LED_0603_1608Metric_G"
		(layer "F.Cu")
		(at 167.675 62.25 -90)
		(descr "LED SMD 0603 Green")
		(tags "LED SMD 0603 Green")
		(property "Reference" "D2"
			(at 9.45 -0.225 90)
			(unlocked yes)
			(layer "F.SilkS")
			(effects
				(font
					(size 0.7 0.7)
					(thickness 0.15)
				)
				(justify right bottom)
			)
		)
		(property "Value" "LED_G_0603_KP-1608CGCK"
			(at -0.001 1.599 90)
			(layer "F.Fab")
			(effects
				(font
					(size 0.7 0.7)
					(thickness 0.15)
				)
				(justify right bottom)
			)
		)
		(property "Author" "Antmicro"
			(at 105.425 229.925 0)
			(layer "F.Fab")
			(hide yes)
			(effects
				(font
					(size 1 1)
					(thickness 0.15)
				)
			)
		)
		(property "License" "Apache-2.0"
			(at 105.425 229.925 0)
			(layer "F.Fab")
			(hide yes)
			(effects
				(font
					(size 1 1)
					(thickness 0.15)
				)
			)
		)
		(property "MPN" "KP-1608CGCK"
			(at 105.425 229.925 0)
			(layer "F.Fab")
			(hide yes)
			(effects
				(font
					(size 1 1)
					(thickness 0.15)
				)
			)
		)
		(property "Manufacturer" "Kingbright"
			(at 105.425 229.925 0)
			(layer "F.Fab")
			(hide yes)
			(effects
				(font
					(size 1 1)
					(thickness 0.15)
				)
			)
		)
		(sheetname "Power supply")
		(sheetfile "power_supply.kicad_sch")
		(attr smd)
		(fp_line
			(start -0.271 0.348)
			(end 0.269 0.348)
			(stroke
				(width 0.15)
				(type solid)
			)
			(layer "F.SilkS")
		)
		(fp_line
			(start 1.249 0.319)
			(end 1.249 -0.321)
			(stroke
				(width 0.15)
				(type solid)
			)
			(layer "F.SilkS")
		)
		(fp_line
			(start -0.107 -0.001)
			(end -0.291 -0.001)
			(stroke
				(width 0.1)
				(type solid)
			)
			(layer "F.SilkS")
		)
		(fp_line
			(start 0.092 -0.001)
			(end -0.107 0.198)
			(stroke
				(width 0.1)
				(type solid)
			)
			(layer "F.SilkS")
		)
		(fp_line
			(start 0.092 -0.001)
			(end 0.292 -0.001)
			(stroke
				(width 0.1)
				(type solid)
			)
			(layer "F.SilkS")
		)
		(fp_line
			(start -0.107 -0.201)
			(end -0.107 0.198)
			(stroke
				(width 0.1)
				(type solid)
			)
			(layer "F.SilkS")
		)
		(fp_line
			(start -0.107 -0.201)
			(end 0.092 -0.001)
			(stroke
				(width 0.1)
				(type solid)
			)
			(layer "F.SilkS")
		)
		(fp_line
			(start 0.092 -0.201)
			(end 0.092 0.198)
			(stroke
				(width 0.1)
				(type solid)
			)
			(layer "F.SilkS")
		)
		(fp_line
			(start -0.271 -0.349)
			(end 0.269 -0.349)
			(stroke
				(width 0.15)
				(type solid)
			)
			(layer "F.SilkS")
		)
		(fp_rect
			(start -1.2192 -0.6096)
			(end 1.27 0.6016)
			(stroke
				(width 0.05)
				(type solid)
			)
			(fill no)
			(layer "F.CrtYd")
		)
		(fp_line
			(start -0.202 0.201)
			(end 0.1 -0.001)
			(stroke
				(width 0.15)
				(type solid)
			)
			(layer "F.Fab")
		)
		(fp_line
			(start 0.198 0.201)
			(end 0.198 -0.101)
			(stroke
				(width 0.15)
				(type solid)
			)
			(layer "F.Fab")
		)
		(fp_line
			(start -0.849 0.025)
			(end -0.442 0.381)
			(stroke
				(width 0.15)
				(type solid)
			)
			(layer "F.Fab")
		)
		(fp_line
			(start -0.6 -0.001)
			(end -0.202 -0.001)
			(stroke
				(width 0.15)
				(type solid)
			)
			(layer "F.Fab")
		)
		(fp_line
			(start -0.202 -0.001)
			(end -0.202 0.201)
			(stroke
				(width 0.15)
				(type solid)
			)
			(layer "F.Fab")
		)
		(fp_line
			(start 0.1 -0.001)
			(end -0.202 -0.201)
			(stroke
				(width 0.15)
				(type solid)
			)
			(layer "F.Fab")
		)
		(fp_line
			(start 0.198 -0.001)
			(end 0.596 -0.001)
			(stroke
				(width 0.15)
				(type solid)
			)
			(layer "F.Fab")
		)
		(fp_line
			(start -0.202 -0.201)
			(end -0.202 -0.001)
			(stroke
				(width 0.15)
				(type solid)
			)
			(layer "F.Fab")
		)
		(fp_line
			(start 0.198 -0.201)
			(end 0.198 -0.101)
			(stroke
				(width 0.15)
				(type solid)
			)
			(layer "F.Fab")
		)
		(fp_rect
			(start -0.849 -0.401)
			(end 0.849 0.401)
			(stroke
				(width 0.15)
				(type solid)
			)
			(fill no)
			(layer "F.Fab")
		)
		(pad "1" smd rect
			(at -0.751 -0.001 90)
			(size 0.8 0.8)
			(layers "F.Cu" "F.Mask" "F.Paste")
			(net 16 "Net-(D2-Pad1)")
			(pinfunction "1")
			(pintype "passive")
		)
		(pad "2" smd rect
			(at 0.749 -0.001 90)
			(size 0.8 0.8)
			(layers "F.Cu" "F.Mask" "F.Paste")
			(net 17 "Net-(D2-Pad2)")
			(pinfunction "2")
			(pintype "passive")
		)
	)
	(footprint "antmicro-footprints:C_0402_1005Metric"
		(layer "F.Cu")
		(at 162.475 70.65)
		(descr "Capacitor SMD 0402")
		(tags "capacitor SMD 0402")
		(property "Reference" "C8"
			(at -0.975 2.45 0)
			(unlocked yes)
			(layer "F.SilkS")
			(effects
				(font
					(size 0.7 0.7)
					(thickness 0.15)
				)
				(justify left bottom)
			)
		)
		(property "Value" "C_4u7_0402"
			(at -1.022927 2.155213 0)
			(layer "F.Fab")
			(effects
				(font
					(size 0.7 0.7)
					(thickness 0.15)
				)
				(justify left bottom)
			)
		)
		(property "Author" "Antmicro"
			(at 0 0 0)
			(layer "F.Fab")
			(hide yes)
			(effects
				(font
					(size 1 1)
					(thickness 0.15)
				)
			)
		)
		(property "Dielectric" ""
			(at 0 0 0)
			(layer "F.Fab")
			(hide yes)
			(effects
				(font
					(size 1 1)
					(thickness 0.15)
				)
			)
		)
		(property "License" "Apache-2.0"
			(at 0 0 0)
			(layer "F.Fab")
			(hide yes)
			(effects
				(font
					(size 1 1)
					(thickness 0.15)
				)
			)
		)
		(property "MPN" "GRM155R61A475MEAAD"
			(at 0 0 0)
			(layer "F.Fab")
			(hide yes)
			(effects
				(font
					(size 1 1)
					(thickness 0.15)
				)
			)
		)
		(property "Manufacturer" "Murata"
			(at 0 0 0)
			(layer "F.Fab")
			(hide yes)
			(effects
				(font
					(size 1 1)
					(thickness 0.15)
				)
			)
		)
		(property "Val" "4u7"
			(at 0 0 0)
			(layer "F.Fab")
			(hide yes)
			(effects
				(font
					(size 1 1)
					(thickness 0.15)
				)
			)
		)
		(property "Voltage" ""
			(at 0 0 0)
			(layer "F.Fab")
			(hide yes)
			(effects
				(font
					(size 1 1)
					(thickness 0.15)
				)
			)
		)
		(sheetname "Power supply")
		(sheetfile "power_supply.kicad_sch")
		(attr smd)
		(fp_rect
			(start -0.9659 -0.481258)
			(end 0.9649 0.458742)
			(stroke
				(width 0.05)
				(type solid)
			)
			(fill no)
			(layer "F.CrtYd")
		)
		(fp_line
			(start -0.499 -0.25)
			(end 0.499 -0.25)
			(stroke
				(width 0.15)
				(type solid)
			)
			(layer "F.Fab")
		)
		(fp_line
			(start -0.499 0.248)
			(end -0.499 -0.25)
			(stroke
				(width 0.15)
				(type solid)
			)
			(layer "F.Fab")
		)
		(fp_line
			(start 0.499 -0.25)
			(end 0.499 0.248)
			(stroke
				(width 0.15)
				(type solid)
			)
			(layer "F.Fab")
		)
		(fp_line
			(start 0.499 0.248)
			(end -0.499 0.248)
			(stroke
				(width 0.15)
				(type solid)
			)
			(layer "F.Fab")
		)
		(pad "1" smd roundrect
			(at -0.484 0)
			(size 0.59 0.64)
			(layers "F.Cu" "F.Mask" "F.Paste")
			(roundrect_rratio 0.25)
			(net 14 "GND")
			(pintype "passive")
		)
		(pad "2" smd roundrect
			(at 0.484 0)
			(size 0.59 0.64)
			(layers "F.Cu" "F.Mask" "F.Paste")
			(roundrect_rratio 0.25)
			(net 1 "+1V1")
			(pintype "passive")
		)
	)
)
